# T6G (Grand Teton) — schematic netlist excerpt (pin names and nets, part order shuffled) for the footprints in the layout excerpt that follows; sources: Cadence DE-HDL packaged netlist, KiCad conversion of 04192023_DAF0TMB3IC0_F0TG_MB_C_brd_V02_OCP.brd

C551  Q_CAP  0.01UF 50V 10% X7R  pkg C0402  page 172 : A = CPU0_HDT_CONN_TESTEN ; B = GND
PC503_1  Q_CAP  0.1UF 25V 10% X7R  pkg 0402  page 225 : A = PVDD11_S3_P1_VCCS ; B = GND

(kicad_pcb
	(version 20260206)
	(generator "pcbnew")
	(generator_version "10.0")
	(general
		(thickness 1.6)
		(legacy_teardrops no)
	)
	(paper "A4")
	(title_block
		(title "04192023_DAF0TMB3IC0_F0TG_MB_C_brd_V02_OCP.brd")
		(comment 1 "Grand Teton / footprints 2613-2614 of 8354")
	)
	(layers
		(0 "F.Cu" signal "TOP")
		(4 "In1.Cu" signal "GND")
		(6 "In2.Cu" signal "IN1")
		(8 "In3.Cu" signal "GND1")
		(10 "In4.Cu" signal "IN2")
		(12 "In5.Cu" signal "GND2")
		(14 "In6.Cu" signal "IN3")
		(16 "In7.Cu" signal "GND3")
		(18 "In8.Cu" signal "VCC")
		(20 "In9.Cu" signal "VCC1")
		(22 "In10.Cu" signal "GND4")
		(24 "In11.Cu" signal "IN4")
		(26 "In12.Cu" signal "GND5")
		(28 "In13.Cu" signal "IN5")
		(30 "In14.Cu" signal "GND6")
		(32 "In15.Cu" signal "IN6")
		(34 "In16.Cu" signal "GND7")
		(2 "B.Cu" signal "BOTTOM")
		(9 "F.Adhes" user "F.Adhesive")
		(11 "B.Adhes" user "B.Adhesive")
		(13 "F.Paste" user "Package Geometry/Pastemask Top")
		(15 "B.Paste" user "Package Geometry/Pastemask Bottom")
		(5 "F.SilkS" user "Ref Des/Silkscreen Top")
		(7 "B.SilkS" user "Ref Des/Silkscreen Bottom")
		(1 "F.Mask" user "Board Geometry/Soldermask Top")
		(3 "B.Mask" user "Board Geometry/Soldermask Bottom")
		(17 "Dwgs.User" user "User.Drawings")
		(19 "Cmts.User" user "User.Comments")
		(21 "Eco1.User" user "User.Eco1")
		(23 "Eco2.User" user "User.Eco2")
		(25 "Edge.Cuts" user "Board Geometry/Outline")
		(27 "Margin" user)
		(31 "F.CrtYd" user "Package Geometry/Place Bound Top")
		(29 "B.CrtYd" user "Package Geometry/Place Bound Bottom")
		(35 "F.Fab" user "Ref Des/Assembly Top")
		(33 "B.Fab" user "Ref Des/Assembly Bottom")
	)
	(footprint ""
		(layer "F.Cu")
		(at 180.225954 -356.152958 90)
		(property "Reference" "PC503_1"
			(at 0 0 90)
			(layer "F.SilkS")
			(hide yes)
			(effects
				(font
					(size 1.27 1.27)
				)
			)
		)
		(property "Value" ""
			(at 0 0 90)
			(layer "F.Fab")
			(effects
				(font
					(size 1.27 1.27)
				)
			)
		)
		(duplicate_pad_numbers_are_jumpers no)
		(fp_line
			(start 0.7874 -0.4064)
			(end 0.7874 0.4064)
			(stroke
				(width 0.1524)
				(type default)
			)
			(layer "F.SilkS")
		)
		(fp_line
			(start -0.7874 -0.4064)
			(end 0.7874 -0.4064)
			(stroke
				(width 0.1524)
				(type default)
			)
			(layer "F.SilkS")
		)
		(fp_line
			(start 0.7874 0.4064)
			(end -0.7874 0.4064)
			(stroke
				(width 0.1524)
				(type default)
			)
			(layer "F.SilkS")
		)
		(fp_line
			(start -0.7874 0.4064)
			(end -0.7874 -0.4064)
			(stroke
				(width 0.1524)
				(type default)
			)
			(layer "F.SilkS")
		)
		(fp_line
			(start -0.12065 -0.305054)
			(end -0.12065 -0.2794)
			(stroke
				(width 0.1)
				(type default)
			)
			(layer "F.Fab")
		)
		(fp_line
			(start -0.67945 -0.305054)
			(end -0.12065 -0.305054)
			(stroke
				(width 0.1)
				(type default)
			)
			(layer "F.Fab")
		)
		(fp_line
			(start 0.67945 -0.3048)
			(end 0.67945 0.3048)
			(stroke
				(width 0.1)
				(type default)
			)
			(layer "F.Fab")
		)
		(fp_line
			(start 0.12065 -0.3048)
			(end 0.67945 -0.3048)
			(stroke
				(width 0.1)
				(type default)
			)
			(layer "F.Fab")
		)
		(fp_line
			(start 0.12065 -0.2794)
			(end 0.12065 -0.3048)
			(stroke
				(width 0.1)
				(type default)
			)
			(layer "F.Fab")
		)
		(fp_line
			(start -0.12065 -0.2794)
			(end 0.12065 -0.2794)
			(stroke
				(width 0.1)
				(type default)
			)
			(layer "F.Fab")
		)
		(fp_line
			(start 0.120396 0.2794)
			(end -0.12065 0.2794)
			(stroke
				(width 0.1)
				(type default)
			)
			(layer "F.Fab")
		)
		(fp_line
			(start -0.12065 0.2794)
			(end -0.12065 0.3048)
			(stroke
				(width 0.1)
				(type default)
			)
			(layer "F.Fab")
		)
		(fp_line
			(start 0.67945 0.3048)
			(end 0.120396 0.3048)
			(stroke
				(width 0.1)
				(type default)
			)
			(layer "F.Fab")
		)
		(fp_line
			(start 0.120396 0.3048)
			(end 0.120396 0.2794)
			(stroke
				(width 0.1)
				(type default)
			)
			(layer "F.Fab")
		)
		(fp_line
			(start -0.12065 0.3048)
			(end -0.67945 0.3048)
			(stroke
				(width 0.1)
				(type default)
			)
			(layer "F.Fab")
		)
		(fp_line
			(start -0.67945 0.3048)
			(end -0.67945 -0.305054)
			(stroke
				(width 0.1)
				(type default)
			)
			(layer "F.Fab")
		)
		(pad "1" smd circle
			(at -0.40005 0 90)
			(size 0 0)
			(layers "F.Cu" "F.Mask" "F.Paste")
			(net "PVDD11_S3_P1_VCCS")
		)
		(pad "2" smd circle
			(at 0.40005 0 90)
			(size 0 0)
			(layers "F.Cu" "F.Mask" "F.Paste")
			(net "GND")
		)
	)
	(footprint ""
		(layer "F.Cu")
		(at 384.390392 -65.541652 -90)
		(property "Reference" "C551"
			(at 0 0 270)
			(layer "F.SilkS")
			(hide yes)
			(effects
				(font
					(size 1.27 1.27)
				)
			)
		)
		(property "Value" ""
			(at 0 0 270)
			(layer "F.Fab")
			(effects
				(font
					(size 1.27 1.27)
				)
			)
		)
		(duplicate_pad_numbers_are_jumpers no)
		(fp_line
			(start -0.7874 0.4064)
			(end -0.7874 -0.4064)
			(stroke
				(width 0.1524)
				(type default)
			)
			(layer "F.SilkS")
		)
		(fp_line
			(start 0.7874 0.4064)
			(end -0.7874 0.4064)
			(stroke
				(width 0.1524)
				(type default)
			)
			(layer "F.SilkS")
		)
		(fp_line
			(start -0.7874 -0.4064)
			(end 0.7874 -0.4064)
			(stroke
				(width 0.1524)
				(type default)
			)
			(layer "F.SilkS")
		)
		(fp_line
			(start 0.7874 -0.4064)
			(end 0.7874 0.4064)
			(stroke
				(width 0.1524)
				(type default)
			)
			(layer "F.SilkS")
		)
		(fp_line
			(start -0.67945 0.3048)
			(end -0.67945 -0.305054)
			(stroke
				(width 0.1)
				(type default)
			)
			(layer "F.Fab")
		)
		(fp_line
			(start -0.12065 0.3048)
			(end -0.67945 0.3048)
			(stroke
				(width 0.1)
				(type default)
			)
			(layer "F.Fab")
		)
		(fp_line
			(start 0.120396 0.3048)
			(end 0.120396 0.2794)
			(stroke
				(width 0.1)
				(type default)
			)
			(layer "F.Fab")
		)
		(fp_line
			(start 0.67945 0.3048)
			(end 0.120396 0.3048)
			(stroke
				(width 0.1)
				(type default)
			)
			(layer "F.Fab")
		)
		(fp_line
			(start -0.12065 0.2794)
			(end -0.12065 0.3048)
			(stroke
				(width 0.1)
				(type default)
			)
			(layer "F.Fab")
		)
		(fp_line
			(start 0.120396 0.2794)
			(end -0.12065 0.2794)
			(stroke
				(width 0.1)
				(type default)
			)
			(layer "F.Fab")
		)
		(fp_line
			(start -0.12065 -0.2794)
			(end 0.12065 -0.2794)
			(stroke
				(width 0.1)
				(type default)
			)
			(layer "F.Fab")
		)
		(fp_line
			(start 0.12065 -0.2794)
			(end 0.12065 -0.3048)
			(stroke
				(width 0.1)
				(type default)
			)
			(layer "F.Fab")
		)
		(fp_line
			(start 0.12065 -0.3048)
			(end 0.67945 -0.3048)
			(stroke
				(width 0.1)
				(type default)
			)
			(layer "F.Fab")
		)
		(fp_line
			(start 0.67945 -0.3048)
			(end 0.67945 0.3048)
			(stroke
				(width 0.1)
				(type default)
			)
			(layer "F.Fab")
		)
		(fp_line
			(start -0.67945 -0.305054)
			(end -0.12065 -0.305054)
			(stroke
				(width 0.1)
				(type default)
			)
			(layer "F.Fab")
		)
		(fp_line
			(start -0.12065 -0.305054)
			(end -0.12065 -0.2794)
			(stroke
				(width 0.1)
				(type default)
			)
			(layer "F.Fab")
		)
		(pad "1" smd circle
			(at -0.40005 0 270)
			(size 0 0)
			(layers "F.Cu" "F.Mask" "F.Paste")
			(net "CPU0_HDT_CONN_TESTEN")
		)
		(pad "2" smd circle
			(at 0.40005 0 270)
			(size 0 0)
			(layers "F.Cu" "F.Mask" "F.Paste")
			(net "GND")
		)
	)
)
